# BASEBOARD_FAB2 (Tioga Pass) — schematic netlist excerpt (pin names and nets, part order shuffled) for the footprints in the layout excerpt that follows; sources: Cadence DE-HDL packaged netlist, KiCad conversion of Wiwynn_Tioga_Pass_MB.brd

R8B8  RES  4.75K 1% CHIP  pkg 0402  page 91 : A = PVPP_ABC ; B = RST_HFI0_CPU0_LVT2_N
C4B5  CAP  1000PF 50V 10% EMPTY  pkg 0402LF  page 234 : A = FM_PVPP_CPU1_EN ; B = AGND_PVPP_KLM
C5D16  CAP_A  22.0UF 4V 20% X6S  pkg 0603V  page 42 : A = PVCCIN_CPU0 ; B = GND

(kicad_pcb
	(version 20260206)
	(generator "pcbnew")
	(generator_version "10.0")
	(general
		(thickness 1.6)
		(legacy_teardrops no)
	)
	(paper "A4")
	(title_block
		(title "Wiwynn_Tioga_Pass_MB.brd")
		(comment 1 "Tioga Pass / footprints 1692-1694 of 4770")
	)
	(layers
		(0 "F.Cu" signal "TOP")
		(4 "In1.Cu" signal "L2GND")
		(6 "In2.Cu" signal "L3")
		(8 "In3.Cu" signal "L4GND")
		(10 "In4.Cu" signal "L5")
		(12 "In5.Cu" signal "L6GND")
		(14 "In6.Cu" signal "L7VCC")
		(16 "In7.Cu" signal "L8VCC")
		(18 "In8.Cu" signal "L9GND")
		(20 "In9.Cu" signal "L10")
		(22 "In10.Cu" signal "L11GND")
		(24 "In11.Cu" signal "L12")
		(26 "In12.Cu" signal "L13GND")
		(2 "B.Cu" signal "BOTTOM")
		(9 "F.Adhes" user "F.Adhesive")
		(11 "B.Adhes" user "B.Adhesive")
		(13 "F.Paste" user "Package Geometry/Pastemask Top")
		(15 "B.Paste" user "Package Geometry/Pastemask Bottom")
		(5 "F.SilkS" user "Ref Des/Silkscreen Top")
		(7 "B.SilkS" user "Ref Des/Silkscreen Bottom")
		(1 "F.Mask" user "Board Geometry/Soldermask Top")
		(3 "B.Mask" user "Board Geometry/Soldermask Bottom")
		(17 "Dwgs.User" user "User.Drawings")
		(19 "Cmts.User" user "User.Comments")
		(21 "Eco1.User" user "User.Eco1")
		(23 "Eco2.User" user "User.Eco2")
		(25 "Edge.Cuts" user "Board Geometry/Outline")
		(27 "Margin" user)
		(31 "F.CrtYd" user "Package Geometry/Place Bound Top")
		(29 "B.CrtYd" user "Package Geometry/Place Bound Bottom")
		(35 "F.Fab" user "Ref Des/Assembly Top")
		(33 "B.Fab" user "Ref Des/Assembly Bottom")
	)
	(footprint ""
		(layer "F.Cu")
		(at 172.466 -131.5085)
		(property "Reference" "C4B5"
			(at 0 0 0)
			(layer "F.SilkS")
			(hide yes)
			(effects
				(font
					(size 1.27 1.27)
				)
			)
		)
		(property "Value" ""
			(at 0 0 0)
			(layer "F.Fab")
			(effects
				(font
					(size 1.27 1.27)
				)
			)
		)
		(duplicate_pad_numbers_are_jumpers no)
		(fp_poly
			(pts
				(xy 0.3048 -0.1016) (xy 0.3048 0.9906) (xy -0.3048 0.9906) (xy -0.3048 -0.1016)
			)
			(stroke
				(width 0)
				(type default)
			)
			(fill no)
			(layer "F.CrtYd")
		)
		(fp_line
			(start -0.3048 -0.1016)
			(end -0.3048 0.9906)
			(stroke
				(width 0.1)
				(type default)
			)
			(layer "F.Fab")
		)
		(fp_line
			(start -0.3048 0.9906)
			(end 0.3048 0.9906)
			(stroke
				(width 0.1)
				(type default)
			)
			(layer "F.Fab")
		)
		(fp_line
			(start 0.3048 -0.1016)
			(end -0.3048 -0.1016)
			(stroke
				(width 0.1)
				(type default)
			)
			(layer "F.Fab")
		)
		(fp_line
			(start 0.3048 0.9906)
			(end 0.3048 -0.1016)
			(stroke
				(width 0.1)
				(type default)
			)
			(layer "F.Fab")
		)
		(pad "1" smd rect
			(at 0 0)
			(size 0.508 0.508)
			(layers "F.Cu" "F.Mask" "F.Paste")
			(net "FM_PVPP_CPU1_EN")
		)
		(pad "2" smd rect
			(at 0 0.889)
			(size 0.508 0.508)
			(layers "F.Cu" "F.Mask" "F.Paste")
			(net "AGND_PVPP_KLM")
		)
		(zone
			(layer "F.Cu")
			(hatch none 0.5)
			(connect_pads
				(clearance 0)
			)
			(min_thickness 0.25)
			(keepout
				(tracks allowed)
				(vias not_allowed)
				(pads allowed)
				(copperpour not_allowed)
				(footprints allowed)
			)
			(placement
				(enabled no)
				(sheetname "")
			)
			(fill
				(thermal_gap 0.5)
				(thermal_bridge_width 0.5)
				(island_removal_mode 0)
			)
			(polygon
				(pts
					(xy 172.212 -131.2545) (xy 172.72 -131.2545) (xy 172.72 -130.8735) (xy 172.212 -130.8735)
				)
			)
		)
		(zone
			(layer "F.Cu")
			(hatch none 0.5)
			(connect_pads
				(clearance 0)
			)
			(min_thickness 0.25)
			(keepout
				(tracks not_allowed)
				(vias allowed)
				(pads allowed)
				(copperpour not_allowed)
				(footprints allowed)
			)
			(placement
				(enabled no)
				(sheetname "")
			)
			(fill
				(thermal_gap 0.5)
				(thermal_bridge_width 0.5)
				(island_removal_mode 0)
			)
			(polygon
				(pts
					(xy 172.212 -130.8735) (xy 172.72 -130.8735) (xy 172.72 -131.2545) (xy 172.212 -131.2545)
				)
			)
		)
	)
	(footprint ""
		(layer "F.Cu")
		(at 264.4394 -79.6036 180)
		(property "Reference" "C5D16"
			(at 0 0 180)
			(layer "F.SilkS")
			(hide yes)
			(effects
				(font
					(size 1.27 1.27)
				)
			)
		)
		(property "Value" ""
			(at 0 0 180)
			(layer "F.Fab")
			(effects
				(font
					(size 1.27 1.27)
				)
			)
		)
		(duplicate_pad_numbers_are_jumpers no)
		(fp_poly
			(pts
				(xy -0.4953 -0.2032) (xy 0.4953 -0.2032) (xy 0.4953 1.6002) (xy -0.4953 1.6002)
			)
			(stroke
				(width 0)
				(type default)
			)
			(fill no)
			(layer "F.CrtYd")
		)
		(fp_line
			(start 0.4953 1.6002)
			(end -0.4953 1.6002)
			(stroke
				(width 0.1)
				(type default)
			)
			(layer "F.Fab")
		)
		(fp_line
			(start 0.4953 -0.2032)
			(end 0.4953 1.6002)
			(stroke
				(width 0.1)
				(type default)
			)
			(layer "F.Fab")
		)
		(fp_line
			(start -0.4953 1.6002)
			(end -0.4953 -0.2032)
			(stroke
				(width 0.1)
				(type default)
			)
			(layer "F.Fab")
		)
		(fp_line
			(start -0.4953 -0.2032)
			(end 0.4953 -0.2032)
			(stroke
				(width 0.1)
				(type default)
			)
			(layer "F.Fab")
		)
		(pad "1" smd rect
			(at 0 0 180)
			(size 0.762 0.889)
			(layers "F.Cu" "F.Mask" "F.Paste")
			(net "PVCCIN_CPU0")
		)
		(pad "2" smd rect
			(at 0 1.397 180)
			(size 0.762 0.889)
			(layers "F.Cu" "F.Mask" "F.Paste")
			(net "GND")
		)
		(zone
			(layer "F.Cu")
			(hatch none 0.5)
			(connect_pads
				(clearance 0)
			)
			(min_thickness 0.25)
			(keepout
				(tracks not_allowed)
				(vias allowed)
				(pads allowed)
				(copperpour not_allowed)
				(footprints allowed)
			)
			(placement
				(enabled no)
				(sheetname "")
			)
			(fill
				(thermal_gap 0.5)
				(thermal_bridge_width 0.5)
				(island_removal_mode 0)
			)
			(polygon
				(pts
					(xy 264.8204 -80.0481) (xy 264.0584 -80.0481) (xy 264.0584 -80.5561) (xy 264.8204 -80.5561)
				)
			)
		)
	)
	(footprint ""
		(layer "F.Cu")
		(at 426.5295 -128.1557 -90)
		(property "Reference" "R8B8"
			(at 0 0 270)
			(layer "F.SilkS")
			(hide yes)
			(effects
				(font
					(size 1.27 1.27)
				)
			)
		)
		(property "Value" ""
			(at 0 0 270)
			(layer "F.Fab")
			(effects
				(font
					(size 1.27 1.27)
				)
			)
		)
		(duplicate_pad_numbers_are_jumpers no)
		(fp_poly
			(pts
				(xy -0.2794 -0.1016) (xy 0.2794 -0.1016) (xy 0.2794 0.9906) (xy -0.2794 0.9906)
			)
			(stroke
				(width 0)
				(type default)
			)
			(fill no)
			(layer "F.CrtYd")
		)
		(fp_line
			(start -0.2794 0.9906)
			(end 0.2794 0.9906)
			(stroke
				(width 0.1)
				(type default)
			)
			(layer "F.Fab")
		)
		(fp_line
			(start 0.2794 0.9906)
			(end 0.2794 -0.1016)
			(stroke
				(width 0.1)
				(type default)
			)
			(layer "F.Fab")
		)
		(fp_line
			(start -0.2794 -0.1016)
			(end -0.2794 0.9906)
			(stroke
				(width 0.1)
				(type default)
			)
			(layer "F.Fab")
		)
		(fp_line
			(start 0.2794 -0.1016)
			(end -0.2794 -0.1016)
			(stroke
				(width 0.1)
				(type default)
			)
			(layer "F.Fab")
		)
		(pad "1" smd rect
			(at 0 0 270)
			(size 0.508 0.508)
			(layers "F.Cu" "F.Mask" "F.Paste")
			(net "PVPP_ABC")
		)
		(pad "2" smd rect
			(at 0 0.889 270)
			(size 0.508 0.508)
			(layers "F.Cu" "F.Mask" "F.Paste")
			(net "RST_HFI0_CPU0_LVT2_N")
		)
		(zone
			(layer "F.Cu")
			(hatch none 0.5)
			(connect_pads
				(clearance 0)
			)
			(min_thickness 0.25)
			(keepout
				(tracks not_allowed)
				(vias allowed)
				(pads allowed)
				(copperpour not_allowed)
				(footprints allowed)
			)
			(placement
				(enabled no)
				(sheetname "")
			)
			(fill
				(thermal_gap 0.5)
				(thermal_bridge_width 0.5)
				(island_removal_mode 0)
			)
			(polygon
				(pts
					(xy 425.8945 -128.4097) (xy 425.8945 -127.9017) (xy 426.2755 -127.9017) (xy 426.2755 -128.4097)
				)
			)
		)
		(zone
			(layer "F.Cu")
			(hatch none 0.5)
			(connect_pads
				(clearance 0)
			)
			(min_thickness 0.25)
			(keepout
				(tracks allowed)
				(vias not_allowed)
				(pads allowed)
				(copperpour not_allowed)
				(footprints allowed)
			)
			(placement
				(enabled no)
				(sheetname "")
			)
			(fill
				(thermal_gap 0.5)
				(thermal_bridge_width 0.5)
				(island_removal_mode 0)
			)
			(polygon
				(pts
					(xy 426.2755 -128.4097) (xy 426.2755 -127.9017) (xy 425.8945 -127.9017) (xy 425.8945 -128.4097)
				)
			)
		)
	)
)
